(kicad_pcb
	(version 20241229)
	(generator "pcbnew")
	(generator_version "9.0")
	(general
		(thickness 1.711)
		(legacy_teardrops no)
	)
	(paper "A4")
	(title_block
		(title "Antmicro Baseboard for Jetson AGX Thor")
		(date "2026-02-18")
		(rev "1.1.0")
		(company "Antmicro Ltd")
		(comment 1 "www.antmicro.com")
		(comment 9 "footprint 710 of 1170 (J18), pads 280-370 of 564")
	)
	(layers
		(0 "F.Cu" signal)
		(4 "In1.Cu" signal)
		(6 "In2.Cu" signal)
		(8 "In3.Cu" signal)
		(10 "In4.Cu" jumper)
		(12 "In5.Cu" signal)
		(14 "In6.Cu" signal)
		(16 "In7.Cu" signal)
		(18 "In8.Cu" signal)
		(2 "B.Cu" signal)
		(9 "F.Adhes" user "F.Adhesive")
		(11 "B.Adhes" user "B.Adhesive")
		(13 "F.Paste" user)
		(15 "B.Paste" user)
		(5 "F.SilkS" user "F.Silkscreen")
		(7 "B.SilkS" user "B.Silkscreen")
		(1 "F.Mask" user)
		(3 "B.Mask" user)
		(17 "Dwgs.User" user "User.Drawings")
		(19 "Cmts.User" user "User.Comments")
		(21 "Eco1.User" user "User.Eco1")
		(23 "Eco2.User" user "User.Eco2")
		(25 "Edge.Cuts" user)
		(27 "Margin" user)
		(31 "F.CrtYd" user "F.Courtyard")
		(29 "B.CrtYd" user "B.Courtyard")
		(35 "F.Fab" user)
		(33 "B.Fab" user)
	)
	(footprint "antmicro-footprints:ASP-208571-01_mounting_holes"
		(locked yes)
		(layer "B.Cu")
		(at 77.680532 103.71 90)
		(property "Reference" "J18"
			(at -25.89 11.119468 270)
			(layer "B.SilkS")
			(effects
				(font
					(size 0.7 0.7)
					(thickness 0.15)
				)
				(justify left bottom mirror)
			)
		)
		(property "Value" "ASP-208571-01_mounting_holes"
			(at -15.05 -10.885 270)
			(layer "B.Fab")
			(effects
				(font
					(size 0.7 0.7)
					(thickness 0.15)
				)
				(justify left bottom mirror)
			)
		)
		(property "Datasheet" "https://suddendocs.samtec.com/prints/asp-208571-01-mkt.pdf"
			(at 0 0 270)
			(layer "B.Fab")
			(hide yes)
			(effects
				(font
					(size 1.27 1.27)
					(thickness 0.15)
				)
				(justify mirror)
			)
		)
		(property "Description" "FMC connector"
			(at 0 0 270)
			(layer "B.Fab")
			(hide yes)
			(effects
				(font
					(size 1.27 1.27)
					(thickness 0.15)
				)
				(justify mirror)
			)
		)
		(property "MPN" "ASP-208571-01"
			(at 0 0 90)
			(unlocked yes)
			(layer "B.Fab")
			(hide yes)
			(effects
				(font
					(size 1 1)
					(thickness 0.15)
				)
				(justify mirror)
			)
		)
		(property "Manufacturer" "Samtec"
			(at 0 0 90)
			(unlocked yes)
			(layer "B.Fab")
			(hide yes)
			(effects
				(font
					(size 1 1)
					(thickness 0.15)
				)
				(justify mirror)
			)
		)
		(property "Author" "Antmicro"
			(at 0 0 90)
			(unlocked yes)
			(layer "B.Fab")
			(hide yes)
			(effects
				(font
					(size 1 1)
					(thickness 0.15)
				)
				(justify mirror)
			)
		)
		(property "License" "Apache-2.0"
			(at 0 0 90)
			(unlocked yes)
			(layer "B.Fab")
			(hide yes)
			(effects
				(font
					(size 1 1)
					(thickness 0.15)
				)
				(justify mirror)
			)
		)
		(sheetname "/Expansion connector/")
		(sheetfile "expansion_connector.kicad_sch")
		(attr smd)
		(pad "G36" smd circle
			(at -19.685 -1.905 90)
			(size 0.64 0.64)
			(layers "B.Cu" "B.Mask")
			(net 300 "unconnected-(J18-PadG36)")
			(pinfunction "G36")
			(pintype "passive+no_connect")
		)
		(pad "G37" smd circle
			(at -20.955 -1.905 90)
			(size 0.64 0.64)
			(layers "B.Cu" "B.Mask")
			(net 308 "unconnected-(J18-PadG37)")
			(pinfunction "G37")
			(pintype "passive+no_connect")
		)
		(pad "G38" smd circle
			(at -22.225 -1.905 90)
			(size 0.64 0.64)
			(layers "B.Cu" "B.Mask")
			(net 1 "GND")
			(pinfunction "G38")
			(pintype "passive")
		)
		(pad "G39" smd circle
			(at -23.495 -1.905 90)
			(size 0.64 0.64)
			(layers "B.Cu" "B.Mask")
			(net 295 "/Expansion connector/+V_{ADJ}")
			(pinfunction "G39")
			(pintype "passive")
		)
		(pad "G40" smd circle
			(at -24.765 -1.905 90)
			(size 0.64 0.64)
			(layers "B.Cu" "B.Mask")
			(net 1 "GND")
			(pinfunction "G40")
			(pintype "passive")
		)
		(pad "H01" smd circle
			(at 24.765 -3.175 90)
			(size 0.64 0.64)
			(layers "B.Cu" "B.Mask")
			(net 431 "Net-(J18-PadH01)")
			(pinfunction "H01")
			(pintype "passive")
		)
		(pad "H02" smd circle
			(at 23.495 -3.175 90)
			(size 0.64 0.64)
			(layers "B.Cu" "B.Mask")
			(net 761 "Net-(J18-PadH02)")
			(pinfunction "H02")
			(pintype "passive")
		)
		(pad "H03" smd circle
			(at 22.225 -3.175 90)
			(size 0.64 0.64)
			(layers "B.Cu" "B.Mask")
			(net 1 "GND")
			(pinfunction "H03")
			(pintype "passive")
		)
		(pad "H04" smd circle
			(at 20.955 -3.175 90)
			(size 0.64 0.64)
			(layers "B.Cu" "B.Mask")
			(net 432 "unconnected-(J18-PadH04)")
			(pinfunction "H04")
			(pintype "passive+no_connect")
		)
		(pad "H05" smd circle
			(at 19.685 -3.175 90)
			(size 0.64 0.64)
			(layers "B.Cu" "B.Mask")
			(net 852 "unconnected-(J18-PadH05)")
			(pinfunction "H05")
			(pintype "passive+no_connect")
		)
		(pad "H06" smd circle
			(at 18.415 -3.175 90)
			(size 0.64 0.64)
			(layers "B.Cu" "B.Mask")
			(net 1 "GND")
			(pinfunction "H06")
			(pintype "passive")
		)
		(pad "H07" smd circle
			(at 17.145 -3.175 90)
			(size 0.64 0.64)
			(layers "B.Cu" "B.Mask")
			(net 105 "/Expansion connector/CAN0.DIN")
			(pinfunction "H07")
			(pintype "passive")
		)
		(pad "H08" smd circle
			(at 15.875 -3.175 90)
			(size 0.64 0.64)
			(layers "B.Cu" "B.Mask")
			(net 142 "/Expansion connector/CAN0.DOUT")
			(pinfunction "H08")
			(pintype "passive")
		)
		(pad "H09" smd circle
			(at 14.605 -3.175 90)
			(size 0.64 0.64)
			(layers "B.Cu" "B.Mask")
			(net 1 "GND")
			(pinfunction "H09")
			(pintype "passive")
		)
		(pad "H10" smd circle
			(at 13.335 -3.175 90)
			(size 0.64 0.64)
			(layers "B.Cu" "B.Mask")
			(net 50 "/Expansion connector/CAN1.DIN")
			(pinfunction "H10")
			(pintype "passive")
		)
		(pad "H11" smd circle
			(at 12.065 -3.175 90)
			(size 0.64 0.64)
			(layers "B.Cu" "B.Mask")
			(net 81 "/Expansion connector/CAN1.DOUT")
			(pinfunction "H11")
			(pintype "passive")
		)
		(pad "H12" smd circle
			(at 10.795 -3.175 90)
			(size 0.64 0.64)
			(layers "B.Cu" "B.Mask")
			(net 1 "GND")
			(pinfunction "H12")
			(pintype "passive")
		)
		(pad "H13" smd circle
			(at 9.525 -3.175 90)
			(size 0.64 0.64)
			(layers "B.Cu" "B.Mask")
			(net 690 "/Expansion connector/CAN2.DIN")
			(pinfunction "H13")
			(pintype "passive")
		)
		(pad "H14" smd circle
			(at 8.255 -3.175 90)
			(size 0.64 0.64)
			(layers "B.Cu" "B.Mask")
			(net 600 "/Expansion connector/CAN2.DOUT")
			(pinfunction "H14")
			(pintype "passive")
		)
		(pad "H15" smd circle
			(at 6.985 -3.175 90)
			(size 0.64 0.64)
			(layers "B.Cu" "B.Mask")
			(net 1 "GND")
			(pinfunction "H15")
			(pintype "passive")
		)
		(pad "H16" smd circle
			(at 5.715 -3.175 90)
			(size 0.64 0.64)
			(layers "B.Cu" "B.Mask")
			(net 701 "/Expansion connector/CAN3.DIN")
			(pinfunction "H16")
			(pintype "passive")
		)
		(pad "H17" smd circle
			(at 4.445 -3.175 90)
			(size 0.64 0.64)
			(layers "B.Cu" "B.Mask")
			(net 783 "/Expansion connector/CAN3.DOUT")
			(pinfunction "H17")
			(pintype "passive")
		)
		(pad "H18" smd circle
			(at 3.175 -3.175 90)
			(size 0.64 0.64)
			(layers "B.Cu" "B.Mask")
			(net 1 "GND")
			(pinfunction "H18")
			(pintype "passive")
		)
		(pad "H19" smd circle
			(at 1.905 -3.175 90)
			(size 0.64 0.64)
			(layers "B.Cu" "B.Mask")
			(net 487 "/Expansion connector/GPIO.USER_LED0")
			(pinfunction "H19")
			(pintype "passive")
		)
		(pad "H20" smd circle
			(at 0.635 -3.175 90)
			(size 0.64 0.64)
			(layers "B.Cu" "B.Mask")
			(net 371 "/Expansion connector/GPIO.USER_LED1")
			(pinfunction "H20")
			(pintype "passive")
		)
		(pad "H21" smd circle
			(at -0.635 -3.175 90)
			(size 0.64 0.64)
			(layers "B.Cu" "B.Mask")
			(net 1 "GND")
			(pinfunction "H21")
			(pintype "passive")
		)
		(pad "H22" smd circle
			(at -1.905 -3.175 90)
			(size 0.64 0.64)
			(layers "B.Cu" "B.Mask")
			(net 448 "/Expansion connector/GPIO.USER_BTN0")
			(pinfunction "H22")
			(pintype "passive")
		)
		(pad "H23" smd circle
			(at -3.175 -3.175 90)
			(size 0.64 0.64)
			(layers "B.Cu" "B.Mask")
			(net 356 "/Expansion connector/GPIO.USER_BTN1")
			(pinfunction "H23")
			(pintype "passive")
		)
		(pad "H24" smd circle
			(at -4.445 -3.175 90)
			(size 0.64 0.64)
			(layers "B.Cu" "B.Mask")
			(net 1 "GND")
			(pinfunction "H24")
			(pintype "passive")
		)
		(pad "H25" smd circle
			(at -5.715 -3.175 90)
			(size 0.64 0.64)
			(layers "B.Cu" "B.Mask")
			(net 849 "/Expansion connector/GPIO.18")
			(pinfunction "H25")
			(pintype "passive")
		)
		(pad "H26" smd circle
			(at -6.985 -3.175 90)
			(size 0.64 0.64)
			(layers "B.Cu" "B.Mask")
			(net 464 "/Expansion connector/GPIO.20")
			(pinfunction "H26")
			(pintype "passive")
		)
		(pad "H27" smd circle
			(at -8.255 -3.175 90)
			(size 0.64 0.64)
			(layers "B.Cu" "B.Mask")
			(net 1 "GND")
			(pinfunction "H27")
			(pintype "passive")
		)
		(pad "H28" smd circle
			(at -9.525 -3.175 90)
			(size 0.64 0.64)
			(layers "B.Cu" "B.Mask")
			(net 49 "/Expansion connector/SPI3.MOSI")
			(pinfunction "H28")
			(pintype "passive")
		)
		(pad "H29" smd circle
			(at -10.795 -3.175 90)
			(size 0.64 0.64)
			(layers "B.Cu" "B.Mask")
			(net 305 "/Expansion connector/SPI3.SCK")
			(pinfunction "H29")
			(pintype "passive")
		)
		(pad "H30" smd circle
			(at -12.065 -3.175 90)
			(size 0.64 0.64)
			(layers "B.Cu" "B.Mask")
			(net 1 "GND")
			(pinfunction "H30")
			(pintype "passive")
		)
		(pad "H31" smd circle
			(at -13.335 -3.175 90)
			(size 0.64 0.64)
			(layers "B.Cu" "B.Mask")
			(net 405 "/Expansion connector/SPI3.~{CS1}")
			(pinfunction "H31")
			(pintype "passive")
		)
		(pad "H32" smd circle
			(at -14.605 -3.175 90)
			(size 0.64 0.64)
			(layers "B.Cu" "B.Mask")
			(net 75 "/Expansion connector/SPI3.MISO")
			(pinfunction "H32")
			(pintype "passive")
		)
		(pad "H33" smd circle
			(at -15.875 -3.175 90)
			(size 0.64 0.64)
			(layers "B.Cu" "B.Mask")
			(net 1 "GND")
			(pinfunction "H33")
			(pintype "passive")
		)
		(pad "H34" smd circle
			(at -17.145 -3.175 90)
			(size 0.64 0.64)
			(layers "B.Cu" "B.Mask")
			(net 846 "unconnected-(J18-PadH34)")
			(pinfunction "H34")
			(pintype "passive+no_connect")
		)
		(pad "H35" smd circle
			(at -18.415 -3.175 90)
			(size 0.64 0.64)
			(layers "B.Cu" "B.Mask")
			(net 1360 "unconnected-(J18-PadH35)")
			(pinfunction "H35")
			(pintype "passive+no_connect")
		)
		(pad "H36" smd circle
			(at -19.685 -3.175 90)
			(size 0.64 0.64)
			(layers "B.Cu" "B.Mask")
			(net 1 "GND")
			(pinfunction "H36")
			(pintype "passive")
		)
		(pad "H37" smd circle
			(at -20.955 -3.175 90)
			(size 0.64 0.64)
			(layers "B.Cu" "B.Mask")
			(net 864 "unconnected-(J18-PadH37)")
			(pinfunction "H37")
			(pintype "passive+no_connect")
		)
		(pad "H38" smd circle
			(at -22.225 -3.175 90)
			(size 0.64 0.64)
			(layers "B.Cu" "B.Mask")
			(net 859 "unconnected-(J18-PadH38)")
			(pinfunction "H38")
			(pintype "passive+no_connect")
		)
		(pad "H39" smd circle
			(at -23.495 -3.175 90)
			(size 0.64 0.64)
			(layers "B.Cu" "B.Mask")
			(net 1 "GND")
			(pinfunction "H39")
			(pintype "passive")
		)
		(pad "H40" smd circle
			(at -24.765 -3.175 90)
			(size 0.64 0.64)
			(layers "B.Cu" "B.Mask")
			(net 295 "/Expansion connector/+V_{ADJ}")
			(pinfunction "H40")
			(pintype "passive")
		)
		(pad "J01" smd circle
			(at 24.765 -4.445 90)
			(size 0.64 0.64)
			(layers "B.Cu" "B.Mask")
			(net 1 "GND")
			(pinfunction "J01")
			(pintype "passive")
		)
		(pad "J02" smd circle
			(at 23.495 -4.445 90)
			(size 0.64 0.64)
			(layers "B.Cu" "B.Mask")
			(net 353 "unconnected-(J18-PadJ02)")
			(pinfunction "J02")
			(pintype "passive+no_connect")
		)
		(pad "J03" smd circle
			(at 22.225 -4.445 90)
			(size 0.64 0.64)
			(layers "B.Cu" "B.Mask")
			(net 401 "unconnected-(J18-PadJ03)")
			(pinfunction "J03")
			(pintype "passive+no_connect")
		)
		(pad "J04" smd circle
			(at 20.955 -4.445 90)
			(size 0.64 0.64)
			(layers "B.Cu" "B.Mask")
			(net 1 "GND")
			(pinfunction "J04")
			(pintype "passive")
		)
		(pad "J05" smd circle
			(at 19.685 -4.445 90)
			(size 0.64 0.64)
			(layers "B.Cu" "B.Mask")
			(net 1 "GND")
			(pinfunction "J05")
			(pintype "passive")
		)
		(pad "J06" smd circle
			(at 18.415 -4.445 90)
			(size 0.64 0.64)
			(layers "B.Cu" "B.Mask")
			(net 466 "unconnected-(J18-PadJ06)")
			(pinfunction "J06")
			(pintype "passive+no_connect")
		)
		(pad "J07" smd circle
			(at 17.145 -4.445 90)
			(size 0.64 0.64)
			(layers "B.Cu" "B.Mask")
			(net 352 "unconnected-(J18-PadJ07)")
			(pinfunction "J07")
			(pintype "passive+no_connect")
		)
		(pad "J08" smd circle
			(at 15.875 -4.445 90)
			(size 0.64 0.64)
			(layers "B.Cu" "B.Mask")
			(net 1 "GND")
			(pinfunction "J08")
			(pintype "passive")
		)
		(pad "J09" smd circle
			(at 14.605 -4.445 90)
			(size 0.64 0.64)
			(layers "B.Cu" "B.Mask")
			(net 284 "unconnected-(J18-PadJ09)")
			(pinfunction "J09")
			(pintype "passive+no_connect")
		)
		(pad "J10" smd circle
			(at 13.335 -4.445 90)
			(size 0.64 0.64)
			(layers "B.Cu" "B.Mask")
			(net 380 "unconnected-(J18-PadJ10)")
			(pinfunction "J10")
			(pintype "passive+no_connect")
		)
		(pad "J11" smd circle
			(at 12.065 -4.445 90)
			(size 0.64 0.64)
			(layers "B.Cu" "B.Mask")
			(net 1 "GND")
			(pinfunction "J11")
			(pintype "passive")
		)
		(pad "J12" smd circle
			(at 10.795 -4.445 90)
			(size 0.64 0.64)
			(layers "B.Cu" "B.Mask")
			(net 365 "unconnected-(J18-PadJ12)")
			(pinfunction "J12")
			(pintype "passive+no_connect")
		)
		(pad "J13" smd circle
			(at 9.525 -4.445 90)
			(size 0.64 0.64)
			(layers "B.Cu" "B.Mask")
			(net 332 "unconnected-(J18-PadJ13)")
			(pinfunction "J13")
			(pintype "passive+no_connect")
		)
		(pad "J14" smd circle
			(at 8.255 -4.445 90)
			(size 0.64 0.64)
			(layers "B.Cu" "B.Mask")
			(net 1 "GND")
			(pinfunction "J14")
			(pintype "passive")
		)
		(pad "J15" smd circle
			(at 6.985 -4.445 90)
			(size 0.64 0.64)
			(layers "B.Cu" "B.Mask")
			(net 395 "unconnected-(J18-PadJ15)")
			(pinfunction "J15")
			(pintype "passive+no_connect")
		)
		(pad "J16" smd circle
			(at 5.715 -4.445 90)
			(size 0.64 0.64)
			(layers "B.Cu" "B.Mask")
			(net 396 "unconnected-(J18-PadJ16)")
			(pinfunction "J16")
			(pintype "passive+no_connect")
		)
		(pad "J17" smd circle
			(at 4.445 -4.445 90)
			(size 0.64 0.64)
			(layers "B.Cu" "B.Mask")
			(net 1 "GND")
			(pinfunction "J17")
			(pintype "passive")
		)
		(pad "J18" smd circle
			(at 3.175 -4.445 90)
			(size 0.64 0.64)
			(layers "B.Cu" "B.Mask")
			(net 377 "unconnected-(J18-PadJ18)")
			(pinfunction "J18")
			(pintype "passive+no_connect")
		)
		(pad "J19" smd circle
			(at 1.905 -4.445 90)
			(size 0.64 0.64)
			(layers "B.Cu" "B.Mask")
			(net 461 "unconnected-(J18-PadJ19)")
			(pinfunction "J19")
			(pintype "passive+no_connect")
		)
		(pad "J20" smd circle
			(at 0.635 -4.445 90)
			(size 0.64 0.64)
			(layers "B.Cu" "B.Mask")
			(net 1 "GND")
			(pinfunction "J20")
			(pintype "passive")
		)
		(pad "J21" smd circle
			(at -0.635 -4.445 90)
			(size 0.64 0.64)
			(layers "B.Cu" "B.Mask")
			(net 298 "unconnected-(J18-PadJ21)")
			(pinfunction "J21")
			(pintype "passive+no_connect")
		)
		(pad "J22" smd circle
			(at -1.905 -4.445 90)
			(size 0.64 0.64)
			(layers "B.Cu" "B.Mask")
			(net 296 "unconnected-(J18-PadJ22)")
			(pinfunction "J22")
			(pintype "passive+no_connect")
		)
		(pad "J23" smd circle
			(at -3.175 -4.445 90)
			(size 0.64 0.64)
			(layers "B.Cu" "B.Mask")
			(net 1 "GND")
			(pinfunction "J23")
			(pintype "passive")
		)
		(pad "J24" smd circle
			(at -4.445 -4.445 90)
			(size 0.64 0.64)
			(layers "B.Cu" "B.Mask")
			(net 343 "unconnected-(J18-PadJ24)")
			(pinfunction "J24")
			(pintype "passive+no_connect")
		)
		(pad "J25" smd circle
			(at -5.715 -4.445 90)
			(size 0.64 0.64)
			(layers "B.Cu" "B.Mask")
			(net 351 "unconnected-(J18-PadJ25)")
			(pinfunction "J25")
			(pintype "passive+no_connect")
		)
		(pad "J26" smd circle
			(at -6.985 -4.445 90)
			(size 0.64 0.64)
			(layers "B.Cu" "B.Mask")
			(net 1 "GND")
			(pinfunction "J26")
			(pintype "passive")
		)
		(pad "J27" smd circle
			(at -8.255 -4.445 90)
			(size 0.64 0.64)
			(layers "B.Cu" "B.Mask")
			(net 420 "unconnected-(J18-PadJ27)")
			(pinfunction "J27")
			(pintype "passive+no_connect")
		)
		(pad "J28" smd circle
			(at -9.525 -4.445 90)
			(size 0.64 0.64)
			(layers "B.Cu" "B.Mask")
			(net 367 "unconnected-(J18-PadJ28)")
			(pinfunction "J28")
			(pintype "passive+no_connect")
		)
		(pad "J29" smd circle
			(at -10.795 -4.445 90)
			(size 0.64 0.64)
			(layers "B.Cu" "B.Mask")
			(net 1 "GND")
			(pinfunction "J29")
			(pintype "passive")
		)
		(pad "J30" smd circle
			(at -12.065 -4.445 90)
			(size 0.64 0.64)
			(layers "B.Cu" "B.Mask")
			(net 318 "unconnected-(J18-PadJ30)")
			(pinfunction "J30")
			(pintype "passive+no_connect")
		)
		(pad "J31" smd circle
			(at -13.335 -4.445 90)
			(size 0.64 0.64)
			(layers "B.Cu" "B.Mask")
			(net 388 "unconnected-(J18-PadJ31)")
			(pinfunction "J31")
			(pintype "passive+no_connect")
		)
		(pad "J32" smd circle
			(at -14.605 -4.445 90)
			(size 0.64 0.64)
			(layers "B.Cu" "B.Mask")
			(net 1 "GND")
			(pinfunction "J32")
			(pintype "passive")
		)
		(pad "J33" smd circle
			(at -15.875 -4.445 90)
			(size 0.64 0.64)
			(layers "B.Cu" "B.Mask")
			(net 458 "unconnected-(J18-PadJ33)")
			(pinfunction "J33")
			(pintype "passive+no_connect")
		)
		(pad "J34" smd circle
			(at -17.145 -4.445 90)
			(size 0.64 0.64)
			(layers "B.Cu" "B.Mask")
			(net 378 "unconnected-(J18-PadJ34)")
			(pinfunction "J34")
			(pintype "passive+no_connect")
		)
		(pad "J35" smd circle
			(at -18.415 -4.445 90)
			(size 0.64 0.64)
			(layers "B.Cu" "B.Mask")
			(net 1 "GND")
			(pinfunction "J35")
			(pintype "passive")
		)
		(pad "J36" smd circle
			(at -19.685 -4.445 90)
			(size 0.64 0.64)
			(layers "B.Cu" "B.Mask")
			(net 460 "unconnected-(J18-PadJ36)")
			(pinfunction "J36")
			(pintype "passive+no_connect")
		)
		(pad "J37" smd circle
			(at -20.955 -4.445 90)
			(size 0.64 0.64)
			(layers "B.Cu" "B.Mask")
			(net 470 "unconnected-(J18-PadJ37)")
			(pinfunction "J37")
			(pintype "passive+no_connect")
		)
		(pad "J38" smd circle
			(at -22.225 -4.445 90)
			(size 0.64 0.64)
			(layers "B.Cu" "B.Mask")
			(net 1 "GND")
			(pinfunction "J38")
			(pintype "passive")
		)
		(pad "J39" smd circle
			(at -23.495 -4.445 90)
			(size 0.64 0.64)
			(layers "B.Cu" "B.Mask")
			(net 450 "Net-(J18-PadJ39)")
			(pinfunction "J39")
			(pintype "passive")
		)
		(pad "J40" smd circle
			(at -24.765 -4.445 90)
			(size 0.64 0.64)
			(layers "B.Cu" "B.Mask")
			(net 1 "GND")
			(pinfunction "J40")
			(pintype "passive")
		)
		(pad "K01" smd circle
			(at 24.765 -5.715 90)
			(size 0.64 0.64)
			(layers "B.Cu" "B.Mask")
			(net 753 "Net-(J18-PadK01)")
			(pinfunction "K01")
			(pintype "passive")
		)
		(pad "K02" smd circle
			(at 23.495 -5.715 90)
			(size 0.64 0.64)
			(layers "B.Cu" "B.Mask")
			(net 1 "GND")
			(pinfunction "K02")
			(pintype "passive")
		)
		(pad "K03" smd circle
			(at 22.225 -5.715 90)
			(size 0.64 0.64)
			(layers "B.Cu" "B.Mask")
			(net 1 "GND")
			(pinfunction "K03")
			(pintype "passive")
		)
		(pad "K04" smd circle
			(at 20.955 -5.715 90)
			(size 0.64 0.64)
			(layers "B.Cu" "B.Mask")
			(net 366 "unconnected-(J18-PadK04)")
			(pinfunction "K04")
			(pintype "passive+no_connect")
		)
		(pad "K05" smd circle
			(at 19.685 -5.715 90)
			(size 0.64 0.64)
			(layers "B.Cu" "B.Mask")
			(net 426 "unconnected-(J18-PadK05)")
			(pinfunction "K05")
			(pintype "passive+no_connect")
		)
		(pad "K06" smd circle
			(at 18.415 -5.715 90)
			(size 0.64 0.64)
			(layers "B.Cu" "B.Mask")
			(net 1 "GND")
			(pinfunction "K06")
			(pintype "passive")
		)
	)
)
